(kicad_pcb
	(version 20260206)
	(generator "pcbnew")
	(generator_version "10.0")
	(general
		(thickness 1.6)
		(legacy_teardrops no)
	)
	(paper "A4")
	(title_block
		(title "12092022_DA0F0TFB6D0_F0T_FAN_BOARD_MP5048_D_brd_v02_OCP.brd")
		(comment 1 "Grand Teton / footprints 887-893 of 924")
	)
	(layers
		(0 "F.Cu" signal "TOP")
		(4 "In1.Cu" signal "GND")
		(6 "In2.Cu" signal "IN1")
		(8 "In3.Cu" signal "IN2")
		(10 "In4.Cu" signal "GND1")
		(2 "B.Cu" signal "BOTTOM")
		(9 "F.Adhes" user "F.Adhesive")
		(11 "B.Adhes" user "B.Adhesive")
		(13 "F.Paste" user "Package Geometry/Pastemask Top")
		(15 "B.Paste" user "Package Geometry/Pastemask Bottom")
		(5 "F.SilkS" user "Ref Des/Silkscreen Top")
		(7 "B.SilkS" user "Ref Des/Silkscreen Bottom")
		(1 "F.Mask" user "Board Geometry/Soldermask Top")
		(3 "B.Mask" user "Board Geometry/Soldermask Bottom")
		(17 "Dwgs.User" user "User.Drawings")
		(19 "Cmts.User" user "User.Comments")
		(21 "Eco1.User" user "User.Eco1")
		(23 "Eco2.User" user "User.Eco2")
		(25 "Edge.Cuts" user "Board Geometry/Outline")
		(27 "Margin" user)
		(31 "F.CrtYd" user "Package Geometry/Place Bound Top")
		(29 "B.CrtYd" user "Package Geometry/Place Bound Bottom")
		(35 "F.Fab" user "Ref Des/Assembly Top")
		(33 "B.Fab" user "Ref Des/Assembly Bottom")
	)
	(footprint ""
		(layer "B.Cu")
		(at 44.069 -231.648 180)
		(property "Reference" "C2099"
			(at 0 0 0)
			(layer "B.SilkS")
			(hide yes)
			(effects
				(font
					(size 1.27 1.27)
				)
				(justify mirror)
			)
		)
		(property "Value" ""
			(at 0 0 0)
			(layer "B.Fab")
			(effects
				(font
					(size 1.27 1.27)
				)
				(justify mirror)
			)
		)
		(duplicate_pad_numbers_are_jumpers no)
		(fp_line
			(start 2.2098 0.9398)
			(end 2.2098 -0.9398)
			(stroke
				(width 0.1524)
				(type default)
			)
			(layer "B.SilkS")
		)
		(fp_line
			(start 2.2098 -0.9398)
			(end -2.2098 -0.9398)
			(stroke
				(width 0.1524)
				(type default)
			)
			(layer "B.SilkS")
		)
		(fp_line
			(start -2.2098 0.9398)
			(end 2.2098 0.9398)
			(stroke
				(width 0.1524)
				(type default)
			)
			(layer "B.SilkS")
		)
		(fp_line
			(start -2.2098 -0.9398)
			(end -2.2098 0.9398)
			(stroke
				(width 0.1524)
				(type default)
			)
			(layer "B.SilkS")
		)
		(fp_line
			(start 1.700022 0.899922)
			(end 1.700022 -0.899922)
			(stroke
				(width 0.1)
				(type default)
			)
			(layer "B.Fab")
		)
		(fp_line
			(start 1.700022 -0.899922)
			(end -1.700022 -0.899922)
			(stroke
				(width 0.1)
				(type default)
			)
			(layer "B.Fab")
		)
		(fp_line
			(start -1.700022 0.899922)
			(end 1.700022 0.899922)
			(stroke
				(width 0.1)
				(type default)
			)
			(layer "B.Fab")
		)
		(fp_line
			(start -1.700022 -0.899922)
			(end -1.700022 0.899922)
			(stroke
				(width 0.1)
				(type default)
			)
			(layer "B.Fab")
		)
		(pad "1" smd rect
			(at 1.4732 0 180)
			(size 1.1684 1.5748)
			(layers "B.Cu" "B.Mask" "B.Paste")
			(net "P52V_FAN_1")
		)
		(pad "2" smd rect
			(at -1.4732 0 180)
			(size 1.1684 1.5748)
			(layers "B.Cu" "B.Mask" "B.Paste")
			(net "GND")
		)
	)
	(footprint ""
		(layer "B.Cu")
		(at 9.906 -173.863 180)
		(property "Reference" "C1945"
			(at 0 0 0)
			(layer "B.SilkS")
			(hide yes)
			(effects
				(font
					(size 1.27 1.27)
				)
				(justify mirror)
			)
		)
		(property "Value" ""
			(at 0 0 0)
			(layer "B.Fab")
			(effects
				(font
					(size 1.27 1.27)
				)
				(justify mirror)
			)
		)
		(duplicate_pad_numbers_are_jumpers no)
		(fp_line
			(start 0.7874 0.4064)
			(end 0.7874 -0.4064)
			(stroke
				(width 0.1524)
				(type default)
			)
			(layer "B.SilkS")
		)
		(fp_line
			(start 0.7874 -0.4064)
			(end -0.7874 -0.4064)
			(stroke
				(width 0.1524)
				(type default)
			)
			(layer "B.SilkS")
		)
		(fp_line
			(start -0.7874 0.4064)
			(end 0.7874 0.4064)
			(stroke
				(width 0.1524)
				(type default)
			)
			(layer "B.SilkS")
		)
		(fp_line
			(start -0.7874 -0.4064)
			(end -0.7874 0.4064)
			(stroke
				(width 0.1524)
				(type default)
			)
			(layer "B.SilkS")
		)
		(fp_line
			(start 0.67945 0.3048)
			(end 0.67945 -0.305054)
			(stroke
				(width 0.1)
				(type default)
			)
			(layer "B.Fab")
		)
		(fp_line
			(start 0.67945 -0.305054)
			(end 0.12065 -0.305054)
			(stroke
				(width 0.1)
				(type default)
			)
			(layer "B.Fab")
		)
		(fp_line
			(start 0.12065 0.3048)
			(end 0.67945 0.3048)
			(stroke
				(width 0.1)
				(type default)
			)
			(layer "B.Fab")
		)
		(fp_line
			(start 0.12065 0.2794)
			(end 0.12065 0.3048)
			(stroke
				(width 0.1)
				(type default)
			)
			(layer "B.Fab")
		)
		(fp_line
			(start 0.12065 -0.2794)
			(end -0.12065 -0.2794)
			(stroke
				(width 0.1)
				(type default)
			)
			(layer "B.Fab")
		)
		(fp_line
			(start 0.12065 -0.305054)
			(end 0.12065 -0.2794)
			(stroke
				(width 0.1)
				(type default)
			)
			(layer "B.Fab")
		)
		(fp_line
			(start -0.120396 0.3048)
			(end -0.120396 0.2794)
			(stroke
				(width 0.1)
				(type default)
			)
			(layer "B.Fab")
		)
		(fp_line
			(start -0.120396 0.2794)
			(end 0.12065 0.2794)
			(stroke
				(width 0.1)
				(type default)
			)
			(layer "B.Fab")
		)
		(fp_line
			(start -0.12065 -0.2794)
			(end -0.12065 -0.3048)
			(stroke
				(width 0.1)
				(type default)
			)
			(layer "B.Fab")
		)
		(fp_line
			(start -0.12065 -0.3048)
			(end -0.67945 -0.3048)
			(stroke
				(width 0.1)
				(type default)
			)
			(layer "B.Fab")
		)
		(fp_line
			(start -0.67945 0.3048)
			(end -0.120396 0.3048)
			(stroke
				(width 0.1)
				(type default)
			)
			(layer "B.Fab")
		)
		(fp_line
			(start -0.67945 -0.3048)
			(end -0.67945 0.3048)
			(stroke
				(width 0.1)
				(type default)
			)
			(layer "B.Fab")
		)
		(pad "1" smd circle
			(at 0.40005 0)
			(size 0 0)
			(layers "B.Cu" "B.Mask" "B.Paste")
			(net "P3V3_AUX")
		)
		(pad "2" smd circle
			(at -0.40005 0)
			(size 0 0)
			(layers "B.Cu" "B.Mask" "B.Paste")
			(net "GND")
		)
	)
	(footprint ""
		(layer "B.Cu")
		(at 35.179 -250.23699 -90)
		(property "Reference" "PC28"
			(at 0 0 90)
			(layer "B.SilkS")
			(hide yes)
			(effects
				(font
					(size 1.27 1.27)
				)
				(justify mirror)
			)
		)
		(property "Value" ""
			(at 0 0 90)
			(layer "B.Fab")
			(effects
				(font
					(size 1.27 1.27)
				)
				(justify mirror)
			)
		)
		(duplicate_pad_numbers_are_jumpers no)
		(fp_line
			(start -0.7874 0.4064)
			(end 0.7874 0.4064)
			(stroke
				(width 0.1524)
				(type default)
			)
			(layer "B.SilkS")
		)
		(fp_line
			(start 0.7874 0.4064)
			(end 0.7874 -0.4064)
			(stroke
				(width 0.1524)
				(type default)
			)
			(layer "B.SilkS")
		)
		(fp_line
			(start -0.7874 -0.4064)
			(end -0.7874 0.4064)
			(stroke
				(width 0.1524)
				(type default)
			)
			(layer "B.SilkS")
		)
		(fp_line
			(start 0.7874 -0.4064)
			(end -0.7874 -0.4064)
			(stroke
				(width 0.1524)
				(type default)
			)
			(layer "B.SilkS")
		)
		(fp_line
			(start -0.67945 0.3048)
			(end -0.120396 0.3048)
			(stroke
				(width 0.1)
				(type default)
			)
			(layer "B.Fab")
		)
		(fp_line
			(start -0.120396 0.3048)
			(end -0.120396 0.2794)
			(stroke
				(width 0.1)
				(type default)
			)
			(layer "B.Fab")
		)
		(fp_line
			(start 0.12065 0.3048)
			(end 0.67945 0.3048)
			(stroke
				(width 0.1)
				(type default)
			)
			(layer "B.Fab")
		)
		(fp_line
			(start 0.67945 0.3048)
			(end 0.67945 -0.305054)
			(stroke
				(width 0.1)
				(type default)
			)
			(layer "B.Fab")
		)
		(fp_line
			(start -0.120396 0.2794)
			(end 0.12065 0.2794)
			(stroke
				(width 0.1)
				(type default)
			)
			(layer "B.Fab")
		)
		(fp_line
			(start 0.12065 0.2794)
			(end 0.12065 0.3048)
			(stroke
				(width 0.1)
				(type default)
			)
			(layer "B.Fab")
		)
		(fp_line
			(start -0.12065 -0.2794)
			(end -0.12065 -0.3048)
			(stroke
				(width 0.1)
				(type default)
			)
			(layer "B.Fab")
		)
		(fp_line
			(start 0.12065 -0.2794)
			(end -0.12065 -0.2794)
			(stroke
				(width 0.1)
				(type default)
			)
			(layer "B.Fab")
		)
		(fp_line
			(start -0.67945 -0.3048)
			(end -0.67945 0.3048)
			(stroke
				(width 0.1)
				(type default)
			)
			(layer "B.Fab")
		)
		(fp_line
			(start -0.12065 -0.3048)
			(end -0.67945 -0.3048)
			(stroke
				(width 0.1)
				(type default)
			)
			(layer "B.Fab")
		)
		(fp_line
			(start 0.12065 -0.305054)
			(end 0.12065 -0.2794)
			(stroke
				(width 0.1)
				(type default)
			)
			(layer "B.Fab")
		)
		(fp_line
			(start 0.67945 -0.305054)
			(end 0.12065 -0.305054)
			(stroke
				(width 0.1)
				(type default)
			)
			(layer "B.Fab")
		)
		(pad "1" smd circle
			(at 0.40005 0 90)
			(size 0 0)
			(layers "B.Cu" "B.Mask" "B.Paste")
			(net "FAN_1_TIMER")
		)
		(pad "2" smd circle
			(at -0.40005 0 90)
			(size 0 0)
			(layers "B.Cu" "B.Mask" "B.Paste")
			(net "GND")
		)
	)
	(footprint ""
		(layer "B.Cu")
		(at 9.710166 -64.837056 -90)
		(property "Reference" "PR52"
			(at 0 0 90)
			(layer "B.SilkS")
			(hide yes)
			(effects
				(font
					(size 1.27 1.27)
				)
				(justify mirror)
			)
		)
		(property "Value" ""
			(at 0 0 90)
			(layer "B.Fab")
			(effects
				(font
					(size 1.27 1.27)
				)
				(justify mirror)
			)
		)
		(duplicate_pad_numbers_are_jumpers no)
		(fp_line
			(start -0.7874 0.4064)
			(end 0.7874 0.4064)
			(stroke
				(width 0.1524)
				(type default)
			)
			(layer "B.SilkS")
		)
		(fp_line
			(start 0.7874 0.4064)
			(end 0.7874 -0.4064)
			(stroke
				(width 0.1524)
				(type default)
			)
			(layer "B.SilkS")
		)
		(fp_line
			(start -0.7874 -0.4064)
			(end -0.7874 0.4064)
			(stroke
				(width 0.1524)
				(type default)
			)
			(layer "B.SilkS")
		)
		(fp_line
			(start 0.7874 -0.4064)
			(end -0.7874 -0.4064)
			(stroke
				(width 0.1524)
				(type default)
			)
			(layer "B.SilkS")
		)
		(fp_line
			(start -0.67945 0.3048)
			(end -0.120396 0.3048)
			(stroke
				(width 0.1)
				(type default)
			)
			(layer "B.Fab")
		)
		(fp_line
			(start -0.120396 0.3048)
			(end -0.120396 0.2794)
			(stroke
				(width 0.1)
				(type default)
			)
			(layer "B.Fab")
		)
		(fp_line
			(start 0.12065 0.3048)
			(end 0.67945 0.3048)
			(stroke
				(width 0.1)
				(type default)
			)
			(layer "B.Fab")
		)
		(fp_line
			(start 0.67945 0.3048)
			(end 0.67945 -0.305054)
			(stroke
				(width 0.1)
				(type default)
			)
			(layer "B.Fab")
		)
		(fp_line
			(start -0.120396 0.2794)
			(end 0.12065 0.2794)
			(stroke
				(width 0.1)
				(type default)
			)
			(layer "B.Fab")
		)
		(fp_line
			(start 0.12065 0.2794)
			(end 0.12065 0.3048)
			(stroke
				(width 0.1)
				(type default)
			)
			(layer "B.Fab")
		)
		(fp_line
			(start -0.12065 -0.2794)
			(end -0.12065 -0.3048)
			(stroke
				(width 0.1)
				(type default)
			)
			(layer "B.Fab")
		)
		(fp_line
			(start 0.12065 -0.2794)
			(end -0.12065 -0.2794)
			(stroke
				(width 0.1)
				(type default)
			)
			(layer "B.Fab")
		)
		(fp_line
			(start -0.67945 -0.3048)
			(end -0.67945 0.3048)
			(stroke
				(width 0.1)
				(type default)
			)
			(layer "B.Fab")
		)
		(fp_line
			(start -0.12065 -0.3048)
			(end -0.67945 -0.3048)
			(stroke
				(width 0.1)
				(type default)
			)
			(layer "B.Fab")
		)
		(fp_line
			(start 0.12065 -0.305054)
			(end 0.12065 -0.2794)
			(stroke
				(width 0.1)
				(type default)
			)
			(layer "B.Fab")
		)
		(fp_line
			(start 0.67945 -0.305054)
			(end 0.12065 -0.305054)
			(stroke
				(width 0.1)
				(type default)
			)
			(layer "B.Fab")
		)
		(pad "1" smd circle
			(at 0.40005 0 90)
			(size 0 0)
			(layers "B.Cu" "B.Mask" "B.Paste")
			(net "FAN_4_TEMP")
		)
		(pad "2" smd circle
			(at -0.40005 0 90)
			(size 0 0)
			(layers "B.Cu" "B.Mask" "B.Paste")
			(net "GND")
		)
	)
	(footprint ""
		(layer "B.Cu")
		(at 6.223 -65.405)
		(property "Reference" "PC3122"
			(at 0 0 0)
			(layer "B.SilkS")
			(hide yes)
			(effects
				(font
					(size 1.27 1.27)
				)
				(justify mirror)
			)
		)
		(property "Value" ""
			(at 0 0 0)
			(layer "B.Fab")
			(effects
				(font
					(size 1.27 1.27)
				)
				(justify mirror)
			)
		)
		(duplicate_pad_numbers_are_jumpers no)
		(fp_line
			(start -0.7874 -0.4064)
			(end -0.7874 0.4064)
			(stroke
				(width 0.1524)
				(type default)
			)
			(layer "B.SilkS")
		)
		(fp_line
			(start -0.7874 0.4064)
			(end 0.7874 0.4064)
			(stroke
				(width 0.1524)
				(type default)
			)
			(layer "B.SilkS")
		)
		(fp_line
			(start 0.7874 -0.4064)
			(end -0.7874 -0.4064)
			(stroke
				(width 0.1524)
				(type default)
			)
			(layer "B.SilkS")
		)
		(fp_line
			(start 0.7874 0.4064)
			(end 0.7874 -0.4064)
			(stroke
				(width 0.1524)
				(type default)
			)
			(layer "B.SilkS")
		)
		(fp_line
			(start -0.67945 -0.3048)
			(end -0.67945 0.3048)
			(stroke
				(width 0.1)
				(type default)
			)
			(layer "B.Fab")
		)
		(fp_line
			(start -0.67945 0.3048)
			(end -0.120396 0.3048)
			(stroke
				(width 0.1)
				(type default)
			)
			(layer "B.Fab")
		)
		(fp_line
			(start -0.12065 -0.3048)
			(end -0.67945 -0.3048)
			(stroke
				(width 0.1)
				(type default)
			)
			(layer "B.Fab")
		)
		(fp_line
			(start -0.12065 -0.2794)
			(end -0.12065 -0.3048)
			(stroke
				(width 0.1)
				(type default)
			)
			(layer "B.Fab")
		)
		(fp_line
			(start -0.120396 0.2794)
			(end 0.12065 0.2794)
			(stroke
				(width 0.1)
				(type default)
			)
			(layer "B.Fab")
		)
		(fp_line
			(start -0.120396 0.3048)
			(end -0.120396 0.2794)
			(stroke
				(width 0.1)
				(type default)
			)
			(layer "B.Fab")
		)
		(fp_line
			(start 0.12065 -0.305054)
			(end 0.12065 -0.2794)
			(stroke
				(width 0.1)
				(type default)
			)
			(layer "B.Fab")
		)
		(fp_line
			(start 0.12065 -0.2794)
			(end -0.12065 -0.2794)
			(stroke
				(width 0.1)
				(type default)
			)
			(layer "B.Fab")
		)
		(fp_line
			(start 0.12065 0.2794)
			(end 0.12065 0.3048)
			(stroke
				(width 0.1)
				(type default)
			)
			(layer "B.Fab")
		)
		(fp_line
			(start 0.12065 0.3048)
			(end 0.67945 0.3048)
			(stroke
				(width 0.1)
				(type default)
			)
			(layer "B.Fab")
		)
		(fp_line
			(start 0.67945 -0.305054)
			(end 0.12065 -0.305054)
			(stroke
				(width 0.1)
				(type default)
			)
			(layer "B.Fab")
		)
		(fp_line
			(start 0.67945 0.3048)
			(end 0.67945 -0.305054)
			(stroke
				(width 0.1)
				(type default)
			)
			(layer "B.Fab")
		)
		(pad "1" smd circle
			(at 0.40005 0 180)
			(size 0 0)
			(layers "B.Cu" "B.Mask" "B.Paste")
			(net "GND")
		)
		(pad "2" smd circle
			(at -0.40005 0 180)
			(size 0 0)
			(layers "B.Cu" "B.Mask" "B.Paste")
			(net "FAN_4_CLREF")
		)
	)
	(footprint ""
		(layer "B.Cu")
		(at 40.894 -132.334 180)
		(property "Reference" "R5427"
			(at 0 0 0)
			(layer "B.SilkS")
			(hide yes)
			(effects
				(font
					(size 1.27 1.27)
				)
				(justify mirror)
			)
		)
		(property "Value" ""
			(at 0 0 0)
			(layer "B.Fab")
			(effects
				(font
					(size 1.27 1.27)
				)
				(justify mirror)
			)
		)
		(duplicate_pad_numbers_are_jumpers no)
		(fp_line
			(start 0.7874 0.4064)
			(end 0.7874 -0.4064)
			(stroke
				(width 0.1524)
				(type default)
			)
			(layer "B.SilkS")
		)
		(fp_line
			(start 0.7874 -0.4064)
			(end -0.7874 -0.4064)
			(stroke
				(width 0.1524)
				(type default)
			)
			(layer "B.SilkS")
		)
		(fp_line
			(start -0.7874 0.4064)
			(end 0.7874 0.4064)
			(stroke
				(width 0.1524)
				(type default)
			)
			(layer "B.SilkS")
		)
		(fp_line
			(start -0.7874 -0.4064)
			(end -0.7874 0.4064)
			(stroke
				(width 0.1524)
				(type default)
			)
			(layer "B.SilkS")
		)
		(fp_line
			(start 0.67945 0.3048)
			(end 0.67945 -0.305054)
			(stroke
				(width 0.1)
				(type default)
			)
			(layer "B.Fab")
		)
		(fp_line
			(start 0.67945 -0.305054)
			(end 0.12065 -0.305054)
			(stroke
				(width 0.1)
				(type default)
			)
			(layer "B.Fab")
		)
		(fp_line
			(start 0.12065 0.3048)
			(end 0.67945 0.3048)
			(stroke
				(width 0.1)
				(type default)
			)
			(layer "B.Fab")
		)
		(fp_line
			(start 0.12065 0.2794)
			(end 0.12065 0.3048)
			(stroke
				(width 0.1)
				(type default)
			)
			(layer "B.Fab")
		)
		(fp_line
			(start 0.12065 -0.2794)
			(end -0.12065 -0.2794)
			(stroke
				(width 0.1)
				(type default)
			)
			(layer "B.Fab")
		)
		(fp_line
			(start 0.12065 -0.305054)
			(end 0.12065 -0.2794)
			(stroke
				(width 0.1)
				(type default)
			)
			(layer "B.Fab")
		)
		(fp_line
			(start -0.120396 0.3048)
			(end -0.120396 0.2794)
			(stroke
				(width 0.1)
				(type default)
			)
			(layer "B.Fab")
		)
		(fp_line
			(start -0.120396 0.2794)
			(end 0.12065 0.2794)
			(stroke
				(width 0.1)
				(type default)
			)
			(layer "B.Fab")
		)
		(fp_line
			(start -0.12065 -0.2794)
			(end -0.12065 -0.3048)
			(stroke
				(width 0.1)
				(type default)
			)
			(layer "B.Fab")
		)
		(fp_line
			(start -0.12065 -0.3048)
			(end -0.67945 -0.3048)
			(stroke
				(width 0.1)
				(type default)
			)
			(layer "B.Fab")
		)
		(fp_line
			(start -0.67945 0.3048)
			(end -0.120396 0.3048)
			(stroke
				(width 0.1)
				(type default)
			)
			(layer "B.Fab")
		)
		(fp_line
			(start -0.67945 -0.3048)
			(end -0.67945 0.3048)
			(stroke
				(width 0.1)
				(type default)
			)
			(layer "B.Fab")
		)
		(pad "1" smd rect
			(at 0.40005 0 180)
			(size 0.4572 0.508)
			(layers "B.Cu" "B.Mask" "B.Paste")
			(net "FAN_0_TACH_OL")
		)
		(pad "2" smd rect
			(at -0.40005 0 180)
			(size 0.4572 0.508)
			(layers "B.Cu" "B.Mask" "B.Paste")
			(net "GND")
		)
	)
	(footprint ""
		(layer "B.Cu")
		(at 45.466 -73.971912 90)
		(property "Reference" "PC33"
			(at 0 0 90)
			(layer "B.SilkS")
			(hide yes)
			(effects
				(font
					(size 1.27 1.27)
				)
				(justify mirror)
			)
		)
		(property "Value" ""
			(at 0 0 90)
			(layer "B.Fab")
			(effects
				(font
					(size 1.27 1.27)
				)
				(justify mirror)
			)
		)
		(duplicate_pad_numbers_are_jumpers no)
		(fp_line
			(start 0.7874 -0.4064)
			(end -0.7874 -0.4064)
			(stroke
				(width 0.1524)
				(type default)
			)
			(layer "B.SilkS")
		)
		(fp_line
			(start -0.7874 -0.4064)
			(end -0.7874 0.4064)
			(stroke
				(width 0.1524)
				(type default)
			)
			(layer "B.SilkS")
		)
		(fp_line
			(start 0.7874 0.4064)
			(end 0.7874 -0.4064)
			(stroke
				(width 0.1524)
				(type default)
			)
			(layer "B.SilkS")
		)
		(fp_line
			(start -0.7874 0.4064)
			(end 0.7874 0.4064)
			(stroke
				(width 0.1524)
				(type default)
			)
			(layer "B.SilkS")
		)
		(fp_line
			(start 0.67945 -0.305054)
			(end 0.12065 -0.305054)
			(stroke
				(width 0.1)
				(type default)
			)
			(layer "B.Fab")
		)
		(fp_line
			(start 0.12065 -0.305054)
			(end 0.12065 -0.2794)
			(stroke
				(width 0.1)
				(type default)
			)
			(layer "B.Fab")
		)
		(fp_line
			(start -0.12065 -0.3048)
			(end -0.67945 -0.3048)
			(stroke
				(width 0.1)
				(type default)
			)
			(layer "B.Fab")
		)
		(fp_line
			(start -0.67945 -0.3048)
			(end -0.67945 0.3048)
			(stroke
				(width 0.1)
				(type default)
			)
			(layer "B.Fab")
		)
		(fp_line
			(start 0.12065 -0.2794)
			(end -0.12065 -0.2794)
			(stroke
				(width 0.1)
				(type default)
			)
			(layer "B.Fab")
		)
		(fp_line
			(start -0.12065 -0.2794)
			(end -0.12065 -0.3048)
			(stroke
				(width 0.1)
				(type default)
			)
			(layer "B.Fab")
		)
		(fp_line
			(start 0.12065 0.2794)
			(end 0.12065 0.3048)
			(stroke
				(width 0.1)
				(type default)
			)
			(layer "B.Fab")
		)
		(fp_line
			(start -0.120396 0.2794)
			(end 0.12065 0.2794)
			(stroke
				(width 0.1)
				(type default)
			)
			(layer "B.Fab")
		)
		(fp_line
			(start 0.67945 0.3048)
			(end 0.67945 -0.305054)
			(stroke
				(width 0.1)
				(type default)
			)
			(layer "B.Fab")
		)
		(fp_line
			(start 0.12065 0.3048)
			(end 0.67945 0.3048)
			(stroke
				(width 0.1)
				(type default)
			)
			(layer "B.Fab")
		)
		(fp_line
			(start -0.120396 0.3048)
			(end -0.120396 0.2794)
			(stroke
				(width 0.1)
				(type default)
			)
			(layer "B.Fab")
		)
		(fp_line
			(start -0.67945 0.3048)
			(end -0.120396 0.3048)
			(stroke
				(width 0.1)
				(type default)
			)
			(layer "B.Fab")
		)
		(pad "1" smd circle
			(at 0.40005 0 270)
			(size 0 0)
			(layers "B.Cu" "B.Mask" "B.Paste")
			(net "FAN_2_SS")
		)
		(pad "2" smd circle
			(at -0.40005 0 270)
			(size 0 0)
			(layers "B.Cu" "B.Mask" "B.Paste")
			(net "GND")
		)
	)
)
